# S9S_MB_2U (Grand Teton) — schematic netlist excerpt (pin names and nets, part order shuffled) for the footprints in the layout excerpt that follows; sources: Cadence DE-HDL packaged netlist, KiCad conversion of 03242023_DA0F0TMBIJ0_F0T_Motherboard_J_brd_V01_OCP.brd

D84  Q_LED  IC  pkg SMLF  page 254 : A = LED_PWRGD_PVCCINFAON_CPU1 ; C = LED_PWRGD_PVCCINFAON_CPU1_D
PC508_P1_5  Q_CAP  1UF 16V 10% X6S  pkg C0402  page 287 : A = SW_P12V_PVCCIN_CPU1_FLT ; B = GND

(kicad_pcb
	(version 20260206)
	(generator "pcbnew")
	(generator_version "10.0")
	(general
		(thickness 1.6)
		(legacy_teardrops no)
	)
	(paper "A4")
	(title_block
		(title "03242023_DA0F0TMBIJ0_F0T_Motherboard_J_brd_V01_OCP.brd")
		(comment 1 "Grand Teton / footprints 2778-2779 of 6105")
	)
	(layers
		(0 "F.Cu" signal "TOP")
		(4 "In1.Cu" signal "GND")
		(6 "In2.Cu" signal "IN1")
		(8 "In3.Cu" signal "GND1")
		(10 "In4.Cu" signal "IN2")
		(12 "In5.Cu" signal "GND2")
		(14 "In6.Cu" signal "IN3")
		(16 "In7.Cu" signal "GND3")
		(18 "In8.Cu" signal "VCC")
		(20 "In9.Cu" signal "VCC1")
		(22 "In10.Cu" signal "GND4")
		(24 "In11.Cu" signal "IN4")
		(26 "In12.Cu" signal "GND5")
		(28 "In13.Cu" signal "IN5")
		(30 "In14.Cu" signal "GND6")
		(32 "In15.Cu" signal "IN6")
		(34 "In16.Cu" signal "GND7")
		(2 "B.Cu" signal "BOTTOM")
		(9 "F.Adhes" user "F.Adhesive")
		(11 "B.Adhes" user "B.Adhesive")
		(13 "F.Paste" user "Package Geometry/Pastemask Top")
		(15 "B.Paste" user "Package Geometry/Pastemask Bottom")
		(5 "F.SilkS" user "Ref Des/Silkscreen Top")
		(7 "B.SilkS" user "Ref Des/Silkscreen Bottom")
		(1 "F.Mask" user "Board Geometry/Soldermask Top")
		(3 "B.Mask" user "Board Geometry/Soldermask Bottom")
		(17 "Dwgs.User" user "User.Drawings")
		(19 "Cmts.User" user "User.Comments")
		(21 "Eco1.User" user "User.Eco1")
		(23 "Eco2.User" user "User.Eco2")
		(25 "Edge.Cuts" user "Board Geometry/Outline")
		(27 "Margin" user)
		(31 "F.CrtYd" user "Package Geometry/Place Bound Top")
		(29 "B.CrtYd" user "Package Geometry/Place Bound Bottom")
		(35 "F.Fab" user "Ref Des/Assembly Top")
		(33 "B.Fab" user "Ref Des/Assembly Bottom")
	)
	(footprint ""
		(layer "F.Cu")
		(at 110.181136 -70.79361)
		(property "Reference" "D84"
			(at -54.939946 50.186082 90)
			(unlocked yes)
			(layer "F.SilkS")
			(effects
				(font
					(size 0.635 0.4064)
					(thickness 0.1524)
				)
				(justify left)
			)
		)
		(property "Value" ""
			(at 0 0 0)
			(layer "F.Fab")
			(effects
				(font
					(size 1.27 1.27)
				)
			)
		)
		(duplicate_pad_numbers_are_jumpers no)
		(fp_line
			(start -0.90678 0.4826)
			(end -0.90678 -0.4699)
			(stroke
				(width 0.1524)
				(type default)
			)
			(layer "F.SilkS")
		)
		(fp_line
			(start -0.89408 -0.4826)
			(end 0.90678 -0.4826)
			(stroke
				(width 0.1524)
				(type default)
			)
			(layer "F.SilkS")
		)
		(fp_line
			(start -0.79248 -0.4826)
			(end 1.03378 -0.4826)
			(stroke
				(width 0.1524)
				(type default)
			)
			(layer "F.SilkS")
		)
		(fp_line
			(start -0.64008 -0.4826)
			(end 1.16078 -0.4826)
			(stroke
				(width 0.1524)
				(type default)
			)
			(layer "F.SilkS")
		)
		(fp_line
			(start 0.90678 -0.4826)
			(end 0.90678 0.4826)
			(stroke
				(width 0.1524)
				(type default)
			)
			(layer "F.SilkS")
		)
		(fp_line
			(start 0.90678 0.4826)
			(end -0.90678 0.4826)
			(stroke
				(width 0.1524)
				(type default)
			)
			(layer "F.SilkS")
		)
		(fp_line
			(start 1.03378 -0.4826)
			(end 1.03378 0.4826)
			(stroke
				(width 0.1524)
				(type default)
			)
			(layer "F.SilkS")
		)
		(fp_line
			(start 1.03378 0.4826)
			(end -0.79248 0.4826)
			(stroke
				(width 0.1524)
				(type default)
			)
			(layer "F.SilkS")
		)
		(fp_line
			(start 1.16078 -0.4826)
			(end 1.16078 0.4826)
			(stroke
				(width 0.1524)
				(type default)
			)
			(layer "F.SilkS")
		)
		(fp_line
			(start 1.16078 0.4826)
			(end -0.64008 0.4826)
			(stroke
				(width 0.1524)
				(type default)
			)
			(layer "F.SilkS")
		)
		(fp_line
			(start -0.499872 -0.249936)
			(end 0.499872 -0.249936)
			(stroke
				(width 0.1)
				(type default)
			)
			(layer "F.Fab")
		)
		(fp_line
			(start -0.499872 0.249936)
			(end -0.499872 -0.249936)
			(stroke
				(width 0.1)
				(type default)
			)
			(layer "F.Fab")
		)
		(fp_line
			(start 0.499872 -0.249936)
			(end 0.499872 0.249936)
			(stroke
				(width 0.1)
				(type default)
			)
			(layer "F.Fab")
		)
		(fp_line
			(start 0.499872 0.249936)
			(end -0.499872 0.249936)
			(stroke
				(width 0.1)
				(type default)
			)
			(layer "F.Fab")
		)
		(pad "A" smd rect
			(at -0.47498 0)
			(size 0.6096 0.7112)
			(layers "F.Cu" "F.Mask" "F.Paste")
			(net "LED_PWRGD_PVCCINFAON_CPU1")
		)
		(pad "C" smd rect
			(at 0.47498 0)
			(size 0.6096 0.7112)
			(layers "F.Cu" "F.Mask" "F.Paste")
			(net "LED_PWRGD_PVCCINFAON_CPU1_D")
		)
	)
	(footprint ""
		(layer "F.Cu")
		(at 133.20903 -337.214718 -90)
		(property "Reference" "PC508_P1_5"
			(at 0 0 270)
			(layer "F.SilkS")
			(hide yes)
			(effects
				(font
					(size 1.27 1.27)
				)
			)
		)
		(property "Value" ""
			(at 0 0 270)
			(layer "F.Fab")
			(effects
				(font
					(size 1.27 1.27)
				)
			)
		)
		(duplicate_pad_numbers_are_jumpers no)
		(fp_line
			(start -0.7874 0.4064)
			(end -0.7874 -0.4064)
			(stroke
				(width 0.1524)
				(type default)
			)
			(layer "F.SilkS")
		)
		(fp_line
			(start 0.7874 0.4064)
			(end -0.7874 0.4064)
			(stroke
				(width 0.1524)
				(type default)
			)
			(layer "F.SilkS")
		)
		(fp_line
			(start -0.7874 -0.4064)
			(end 0.7874 -0.4064)
			(stroke
				(width 0.1524)
				(type default)
			)
			(layer "F.SilkS")
		)
		(fp_line
			(start 0.7874 -0.4064)
			(end 0.7874 0.4064)
			(stroke
				(width 0.1524)
				(type default)
			)
			(layer "F.SilkS")
		)
		(fp_line
			(start -0.67945 0.3048)
			(end -0.67945 -0.305054)
			(stroke
				(width 0.1)
				(type default)
			)
			(layer "F.Fab")
		)
		(fp_line
			(start -0.12065 0.3048)
			(end -0.67945 0.3048)
			(stroke
				(width 0.1)
				(type default)
			)
			(layer "F.Fab")
		)
		(fp_line
			(start 0.120396 0.3048)
			(end 0.120396 0.2794)
			(stroke
				(width 0.1)
				(type default)
			)
			(layer "F.Fab")
		)
		(fp_line
			(start 0.67945 0.3048)
			(end 0.120396 0.3048)
			(stroke
				(width 0.1)
				(type default)
			)
			(layer "F.Fab")
		)
		(fp_line
			(start -0.12065 0.2794)
			(end -0.12065 0.3048)
			(stroke
				(width 0.1)
				(type default)
			)
			(layer "F.Fab")
		)
		(fp_line
			(start 0.120396 0.2794)
			(end -0.12065 0.2794)
			(stroke
				(width 0.1)
				(type default)
			)
			(layer "F.Fab")
		)
		(fp_line
			(start -0.12065 -0.2794)
			(end 0.12065 -0.2794)
			(stroke
				(width 0.1)
				(type default)
			)
			(layer "F.Fab")
		)
		(fp_line
			(start 0.12065 -0.2794)
			(end 0.12065 -0.3048)
			(stroke
				(width 0.1)
				(type default)
			)
			(layer "F.Fab")
		)
		(fp_line
			(start 0.12065 -0.3048)
			(end 0.67945 -0.3048)
			(stroke
				(width 0.1)
				(type default)
			)
			(layer "F.Fab")
		)
		(fp_line
			(start 0.67945 -0.3048)
			(end 0.67945 0.3048)
			(stroke
				(width 0.1)
				(type default)
			)
			(layer "F.Fab")
		)
		(fp_line
			(start -0.67945 -0.305054)
			(end -0.12065 -0.305054)
			(stroke
				(width 0.1)
				(type default)
			)
			(layer "F.Fab")
		)
		(fp_line
			(start -0.12065 -0.305054)
			(end -0.12065 -0.2794)
			(stroke
				(width 0.1)
				(type default)
			)
			(layer "F.Fab")
		)
		(pad "1" smd circle
			(at -0.40005 0 270)
			(size 0 0)
			(layers "F.Cu" "F.Mask" "F.Paste")
			(net "SW_P12V_PVCCIN_CPU1_FLT")
		)
		(pad "2" smd circle
			(at 0.40005 0 270)
			(size 0 0)
			(layers "F.Cu" "F.Mask" "F.Paste")
			(net "GND")
		)
	)
)
